# T6G (Grand Teton) — schematic netlist excerpt (pin names and nets, part order shuffled) for the footprints in the layout excerpt that follows; sources: Cadence DE-HDL packaged netlist, KiCad conversion of 04192023_DAF0TMB3IC0_F0TG_MB_C_brd_V02_OCP.brd

R1158  Q_RES  33 5% EMPTY  pkg 0402LF  page 161 : A = SMB_APML_CPU1_R_SDA ; B = SMB_APML_CPU1_SDA
R1183  Q_RES  1K 1% CHIP  pkg 0402LF  page 103 : A = PWRGD_CHF_CPU1_DIMM ; B = PWRGD_CHAF_CPU1

(kicad_pcb
	(version 20260206)
	(generator "pcbnew")
	(generator_version "10.0")
	(general
		(thickness 1.6)
		(legacy_teardrops no)
	)
	(paper "A4")
	(title_block
		(title "04192023_DAF0TMB3IC0_F0TG_MB_C_brd_V02_OCP.brd")
		(comment 1 "Grand Teton / footprints 6367-6368 of 8354")
	)
	(layers
		(0 "F.Cu" signal "TOP")
		(4 "In1.Cu" signal "GND")
		(6 "In2.Cu" signal "IN1")
		(8 "In3.Cu" signal "GND1")
		(10 "In4.Cu" signal "IN2")
		(12 "In5.Cu" signal "GND2")
		(14 "In6.Cu" signal "IN3")
		(16 "In7.Cu" signal "GND3")
		(18 "In8.Cu" signal "VCC")
		(20 "In9.Cu" signal "VCC1")
		(22 "In10.Cu" signal "GND4")
		(24 "In11.Cu" signal "IN4")
		(26 "In12.Cu" signal "GND5")
		(28 "In13.Cu" signal "IN5")
		(30 "In14.Cu" signal "GND6")
		(32 "In15.Cu" signal "IN6")
		(34 "In16.Cu" signal "GND7")
		(2 "B.Cu" signal "BOTTOM")
		(9 "F.Adhes" user "F.Adhesive")
		(11 "B.Adhes" user "B.Adhesive")
		(13 "F.Paste" user "Package Geometry/Pastemask Top")
		(15 "B.Paste" user "Package Geometry/Pastemask Bottom")
		(5 "F.SilkS" user "Ref Des/Silkscreen Top")
		(7 "B.SilkS" user "Ref Des/Silkscreen Bottom")
		(1 "F.Mask" user "Board Geometry/Soldermask Top")
		(3 "B.Mask" user "Board Geometry/Soldermask Bottom")
		(17 "Dwgs.User" user "User.Drawings")
		(19 "Cmts.User" user "User.Comments")
		(21 "Eco1.User" user "User.Eco1")
		(23 "Eco2.User" user "User.Eco2")
		(25 "Edge.Cuts" user "Board Geometry/Outline")
		(27 "Margin" user)
		(31 "F.CrtYd" user "Package Geometry/Place Bound Top")
		(29 "B.CrtYd" user "Package Geometry/Place Bound Bottom")
		(35 "F.Fab" user "Ref Des/Assembly Top")
		(33 "B.Fab" user "Ref Des/Assembly Bottom")
	)
	(footprint ""
		(layer "B.Cu")
		(at 234.569 -240.411 -90)
		(property "Reference" "R1158"
			(at 0 0 90)
			(layer "B.SilkS")
			(hide yes)
			(effects
				(font
					(size 1.27 1.27)
				)
				(justify mirror)
			)
		)
		(property "Value" ""
			(at 0 0 90)
			(layer "B.Fab")
			(effects
				(font
					(size 1.27 1.27)
				)
				(justify mirror)
			)
		)
		(duplicate_pad_numbers_are_jumpers no)
		(fp_line
			(start -0.7874 0.4064)
			(end 0.7874 0.4064)
			(stroke
				(width 0.1524)
				(type default)
			)
			(layer "B.SilkS")
		)
		(fp_line
			(start 0.7874 0.4064)
			(end 0.7874 -0.4064)
			(stroke
				(width 0.1524)
				(type default)
			)
			(layer "B.SilkS")
		)
		(fp_line
			(start -0.7874 -0.4064)
			(end -0.7874 0.4064)
			(stroke
				(width 0.1524)
				(type default)
			)
			(layer "B.SilkS")
		)
		(fp_line
			(start 0.7874 -0.4064)
			(end -0.7874 -0.4064)
			(stroke
				(width 0.1524)
				(type default)
			)
			(layer "B.SilkS")
		)
		(fp_line
			(start -0.67945 0.3048)
			(end -0.120396 0.3048)
			(stroke
				(width 0.1)
				(type default)
			)
			(layer "B.Fab")
		)
		(fp_line
			(start -0.120396 0.3048)
			(end -0.120396 0.2794)
			(stroke
				(width 0.1)
				(type default)
			)
			(layer "B.Fab")
		)
		(fp_line
			(start 0.12065 0.3048)
			(end 0.67945 0.3048)
			(stroke
				(width 0.1)
				(type default)
			)
			(layer "B.Fab")
		)
		(fp_line
			(start 0.67945 0.3048)
			(end 0.67945 -0.305054)
			(stroke
				(width 0.1)
				(type default)
			)
			(layer "B.Fab")
		)
		(fp_line
			(start -0.120396 0.2794)
			(end 0.12065 0.2794)
			(stroke
				(width 0.1)
				(type default)
			)
			(layer "B.Fab")
		)
		(fp_line
			(start 0.12065 0.2794)
			(end 0.12065 0.3048)
			(stroke
				(width 0.1)
				(type default)
			)
			(layer "B.Fab")
		)
		(fp_line
			(start -0.12065 -0.2794)
			(end -0.12065 -0.3048)
			(stroke
				(width 0.1)
				(type default)
			)
			(layer "B.Fab")
		)
		(fp_line
			(start 0.12065 -0.2794)
			(end -0.12065 -0.2794)
			(stroke
				(width 0.1)
				(type default)
			)
			(layer "B.Fab")
		)
		(fp_line
			(start -0.67945 -0.3048)
			(end -0.67945 0.3048)
			(stroke
				(width 0.1)
				(type default)
			)
			(layer "B.Fab")
		)
		(fp_line
			(start -0.12065 -0.3048)
			(end -0.67945 -0.3048)
			(stroke
				(width 0.1)
				(type default)
			)
			(layer "B.Fab")
		)
		(fp_line
			(start 0.12065 -0.305054)
			(end 0.12065 -0.2794)
			(stroke
				(width 0.1)
				(type default)
			)
			(layer "B.Fab")
		)
		(fp_line
			(start 0.67945 -0.305054)
			(end 0.12065 -0.305054)
			(stroke
				(width 0.1)
				(type default)
			)
			(layer "B.Fab")
		)
		(pad "1" smd rect
			(at 0.40005 0 270)
			(size 0.4572 0.508)
			(layers "B.Cu" "B.Mask" "B.Paste")
			(net "SMB_APML_CPU1_R_SDA")
		)
		(pad "2" smd rect
			(at -0.40005 0 270)
			(size 0.4572 0.508)
			(layers "B.Cu" "B.Mask" "B.Paste")
			(net "SMB_APML_CPU1_SDA")
		)
	)
	(footprint ""
		(layer "B.Cu")
		(at 15.113762 -192.362328 90)
		(property "Reference" "R1183"
			(at 0 0 90)
			(layer "B.SilkS")
			(hide yes)
			(effects
				(font
					(size 1.27 1.27)
				)
				(justify mirror)
			)
		)
		(property "Value" ""
			(at 0 0 90)
			(layer "B.Fab")
			(effects
				(font
					(size 1.27 1.27)
				)
				(justify mirror)
			)
		)
		(duplicate_pad_numbers_are_jumpers no)
		(fp_line
			(start 0.7874 -0.4064)
			(end -0.7874 -0.4064)
			(stroke
				(width 0.1524)
				(type default)
			)
			(layer "B.SilkS")
		)
		(fp_line
			(start -0.7874 -0.4064)
			(end -0.7874 0.4064)
			(stroke
				(width 0.1524)
				(type default)
			)
			(layer "B.SilkS")
		)
		(fp_line
			(start 0.7874 0.4064)
			(end 0.7874 -0.4064)
			(stroke
				(width 0.1524)
				(type default)
			)
			(layer "B.SilkS")
		)
		(fp_line
			(start -0.7874 0.4064)
			(end 0.7874 0.4064)
			(stroke
				(width 0.1524)
				(type default)
			)
			(layer "B.SilkS")
		)
		(fp_line
			(start 0.67945 -0.305054)
			(end 0.12065 -0.305054)
			(stroke
				(width 0.1)
				(type default)
			)
			(layer "B.Fab")
		)
		(fp_line
			(start 0.12065 -0.305054)
			(end 0.12065 -0.2794)
			(stroke
				(width 0.1)
				(type default)
			)
			(layer "B.Fab")
		)
		(fp_line
			(start -0.12065 -0.3048)
			(end -0.67945 -0.3048)
			(stroke
				(width 0.1)
				(type default)
			)
			(layer "B.Fab")
		)
		(fp_line
			(start -0.67945 -0.3048)
			(end -0.67945 0.3048)
			(stroke
				(width 0.1)
				(type default)
			)
			(layer "B.Fab")
		)
		(fp_line
			(start 0.12065 -0.2794)
			(end -0.12065 -0.2794)
			(stroke
				(width 0.1)
				(type default)
			)
			(layer "B.Fab")
		)
		(fp_line
			(start -0.12065 -0.2794)
			(end -0.12065 -0.3048)
			(stroke
				(width 0.1)
				(type default)
			)
			(layer "B.Fab")
		)
		(fp_line
			(start 0.12065 0.2794)
			(end 0.12065 0.3048)
			(stroke
				(width 0.1)
				(type default)
			)
			(layer "B.Fab")
		)
		(fp_line
			(start -0.120396 0.2794)
			(end 0.12065 0.2794)
			(stroke
				(width 0.1)
				(type default)
			)
			(layer "B.Fab")
		)
		(fp_line
			(start 0.67945 0.3048)
			(end 0.67945 -0.305054)
			(stroke
				(width 0.1)
				(type default)
			)
			(layer "B.Fab")
		)
		(fp_line
			(start 0.12065 0.3048)
			(end 0.67945 0.3048)
			(stroke
				(width 0.1)
				(type default)
			)
			(layer "B.Fab")
		)
		(fp_line
			(start -0.120396 0.3048)
			(end -0.120396 0.2794)
			(stroke
				(width 0.1)
				(type default)
			)
			(layer "B.Fab")
		)
		(fp_line
			(start -0.67945 0.3048)
			(end -0.120396 0.3048)
			(stroke
				(width 0.1)
				(type default)
			)
			(layer "B.Fab")
		)
		(pad "1" smd circle
			(at 0.40005 0 270)
			(size 0 0)
			(layers "B.Cu" "B.Mask" "B.Paste")
			(net "PWRGD_CHF_CPU1_DIMM")
		)
		(pad "2" smd circle
			(at -0.40005 0 270)
			(size 0 0)
			(layers "B.Cu" "B.Mask" "B.Paste")
			(net "PWRGD_CHAF_CPU1")
		)
	)
)
